(kicad_pcb
	(version 20260206)
	(generator "pcbnew")
	(generator_version "10.0")
	(general
		(thickness 1.6)
		(legacy_teardrops no)
	)
	(paper "A4")
	(title_block
		(title "peb — Lightning_PEB_BRD.brd")
		(comment 1 "Lightning (Wiwynn / Facebook NVMe JBOF) / footprints 1565-1570 of 2563")
	)
	(layers
		(0 "F.Cu" signal "TOP")
		(4 "In1.Cu" signal "L2GND")
		(6 "In2.Cu" signal "L3")
		(8 "In3.Cu" signal "L4VCC")
		(10 "In4.Cu" signal "L5VCC")
		(12 "In5.Cu" signal "L6")
		(14 "In6.Cu" signal "L7GND")
		(2 "B.Cu" signal "BOTTOM")
		(9 "F.Adhes" user "F.Adhesive")
		(11 "B.Adhes" user "B.Adhesive")
		(13 "F.Paste" user "Package Geometry/Pastemask Top")
		(15 "B.Paste" user "Package Geometry/Pastemask Bottom")
		(5 "F.SilkS" user "Ref Des/Silkscreen Top")
		(7 "B.SilkS" user "Ref Des/Silkscreen Bottom")
		(1 "F.Mask" user "Board Geometry/Soldermask Top")
		(3 "B.Mask" user "Board Geometry/Soldermask Bottom")
		(17 "Dwgs.User" user "User.Drawings")
		(19 "Cmts.User" user "User.Comments")
		(21 "Eco1.User" user "User.Eco1")
		(23 "Eco2.User" user "User.Eco2")
		(25 "Edge.Cuts" user "Board Geometry/Outline")
		(27 "Margin" user)
		(31 "F.CrtYd" user "Package Geometry/Place Bound Top")
		(29 "B.CrtYd" user "Package Geometry/Place Bound Bottom")
		(35 "F.Fab" user "Ref Des/Assembly Top")
		(33 "B.Fab" user "Ref Des/Assembly Bottom")
	)
	(footprint ""
		(layer "F.Cu")
		(at 336.836512 -184.878218 180)
		(property "Reference" "R7975"
			(at 0 0 180)
			(layer "F.SilkS")
			(hide yes)
			(effects
				(font
					(size 1.27 1.27)
				)
			)
		)
		(property "Value" "0R2J-2-GP"
			(at 0.064008 -3.993896 180)
			(unlocked yes)
			(layer "F.Fab")
			(hide yes)
			(effects
				(font
					(size 1.016 1.016)
					(thickness 0.1524)
				)
			)
		)
		(property "Device Type" "R402H16"
			(at 0.064008 -5.517896 180)
			(unlocked yes)
			(layer "F.Fab")
			(hide yes)
			(effects
				(font
					(size 1.016 1.016)
					(thickness 0.1524)
				)
			)
		)
		(duplicate_pad_numbers_are_jumpers no)
		(fp_line
			(start 0.508 -0.9398)
			(end -0.508 -0.9398)
			(stroke
				(width 0.1524)
				(type default)
			)
			(layer "F.SilkS")
		)
		(fp_line
			(start -0.508 -0.9398)
			(end -0.508 0.9398)
			(stroke
				(width 0.1524)
				(type default)
			)
			(layer "F.SilkS")
		)
		(fp_rect
			(start -0.508 0.9398)
			(end 0.508 -0.9398)
			(stroke
				(width 0)
				(type default)
			)
			(fill no)
			(layer "F.CrtYd")
		)
		(fp_rect
			(start -0.508 0.9398)
			(end 0.508 -0.9398)
			(stroke
				(width 0)
				(type default)
			)
			(fill no)
			(layer "F.Fab")
		)
		(pad "1" smd custom
			(at 0 -0.4445 180)
			(size 0.1397 0.1397)
			(layers "F.Cu" "F.Mask" "F.Paste")
			(net "SSD_PERST#14")
			(options
				(clearance outline)
				(anchor circle)
			)
			(primitives
				(gr_poly
					(pts
						(arc
							(start -0.1778 -0.2794)
							(mid -0.249642 -0.249642)
							(end -0.2794 -0.1778)
						)
						(arc
							(start -0.2794 0.1778)
							(mid -0.249642 0.249642)
							(end -0.1778 0.2794)
						)
						(arc
							(start 0.1778 0.2794)
							(mid 0.249642 0.249642)
							(end 0.2794 0.1778)
						)
						(arc
							(start 0.2794 -0.1778)
							(mid 0.249642 -0.249642)
							(end 0.1778 -0.2794)
						)
					)
					(width 0)
					(fill yes)
				)
			)
		)
		(pad "2" smd custom
			(at 0 0.4445 180)
			(size 0.1397 0.1397)
			(layers "F.Cu" "F.Mask" "F.Paste")
			(net "SSD_PERST#14_R")
			(options
				(clearance outline)
				(anchor circle)
			)
			(primitives
				(gr_poly
					(pts
						(arc
							(start -0.1778 -0.2794)
							(mid -0.249642 -0.249642)
							(end -0.2794 -0.1778)
						)
						(arc
							(start -0.2794 0.1778)
							(mid -0.249642 0.249642)
							(end -0.1778 0.2794)
						)
						(arc
							(start 0.1778 0.2794)
							(mid 0.249642 0.249642)
							(end 0.2794 0.1778)
						)
						(arc
							(start 0.2794 -0.1778)
							(mid 0.249642 -0.249642)
							(end 0.1778 -0.2794)
						)
					)
					(width 0)
					(fill yes)
				)
			)
		)
	)
	(footprint ""
		(layer "F.Cu")
		(at 12.192 -108.204 90)
		(property "Reference" "PU5"
			(at 0 0 90)
			(layer "F.SilkS")
			(hide yes)
			(effects
				(font
					(size 1.27 1.27)
				)
			)
		)
		(property "Value" "TPS74801DRCR-1-GP-U"
			(at -3.5306 1.3208 90)
			(unlocked yes)
			(layer "F.Fab")
			(hide yes)
			(effects
				(font
					(size 1.016 1.016)
					(thickness 0.1524)
				)
			)
		)
		(property "Device Type" "DFN10G3-G315175H40"
			(at -3.5306 -0.2032 90)
			(unlocked yes)
			(layer "F.Fab")
			(hide yes)
			(effects
				(font
					(size 1.016 1.016)
					(thickness 0.1524)
				)
			)
		)
		(duplicate_pad_numbers_are_jumpers no)
		(fp_line
			(start -0.9906 -2.794)
			(end -0.9906 -2.286)
			(stroke
				(width 0.1524)
				(type default)
			)
			(layer "F.SilkS")
		)
		(fp_line
			(start -1.6256 -2.5146)
			(end -2.3876 -2.5146)
			(stroke
				(width 0.1524)
				(type default)
			)
			(layer "F.SilkS")
		)
		(fp_line
			(start -2.3876 -2.5146)
			(end -2.3876 -1.7526)
			(stroke
				(width 0.1524)
				(type default)
			)
			(layer "F.SilkS")
		)
		(fp_line
			(start -2.3876 1.7526)
			(end -2.3876 2.5146)
			(stroke
				(width 0.1524)
				(type default)
			)
			(layer "F.SilkS")
		)
		(fp_line
			(start 0.9906 2.286)
			(end 0.9906 3.048)
			(stroke
				(width 0.1524)
				(type default)
			)
			(layer "F.SilkS")
		)
		(fp_line
			(start 2.3876 2.5146)
			(end 2.3876 1.7526)
			(stroke
				(width 0.1524)
				(type default)
			)
			(layer "F.SilkS")
		)
		(fp_line
			(start 1.6256 2.5146)
			(end 2.3876 2.5146)
			(stroke
				(width 0.1524)
				(type default)
			)
			(layer "F.SilkS")
		)
		(fp_line
			(start -2.3876 2.5146)
			(end -1.6256 2.5146)
			(stroke
				(width 0.1524)
				(type default)
			)
			(layer "F.SilkS")
		)
		(fp_poly
			(pts
				(xy 1.6256 -2.5146) (xy 2.3876 -2.5146) (xy 2.3876 -1.7526)
			)
			(stroke
				(width 0)
				(type default)
			)
			(fill yes)
			(layer "F.SilkS")
		)
		(fp_rect
			(start -1.4986 1.4986)
			(end 1.4986 -1.4986)
			(stroke
				(width 0)
				(type default)
			)
			(fill no)
			(layer "F.CrtYd")
		)
		(fp_poly
			(pts
				(xy -2.3876 2.5146) (xy -2.3876 0.00254) (xy -1.4986 0.00254) (xy -1.4986 1.4986) (xy 1.4986 1.4986)
				(xy 1.4986 -1.4986) (xy -1.4986 -1.4986) (xy -1.4986 -0.00254) (xy -2.3876 -0.00254) (xy -2.3876 -2.5146)
				(xy 2.3876 -2.5146) (xy 2.3876 2.5146)
			)
			(stroke
				(width 0)
				(type default)
			)
			(fill no)
			(layer "F.CrtYd")
		)
		(fp_rect
			(start -2.3876 2.5146)
			(end 2.3876 -2.5146)
			(stroke
				(width 0)
				(type default)
			)
			(fill no)
			(layer "F.Fab")
		)
		(pad "1" smd rect
			(at 0.99949 -1.5494 90)
			(size 0.3048 0.9144)
			(layers "F.Cu" "F.Mask" "F.Paste")
			(net "VR_P1V26_STBY_IN")
		)
		(pad "2" smd rect
			(at 0.50038 -1.5494 90)
			(size 0.3048 0.9144)
			(layers "F.Cu" "F.Mask" "F.Paste")
			(net "VR_P1V26_STBY_IN")
		)
		(pad "3" smd rect
			(at 0 -1.5494 90)
			(size 0.3048 0.9144)
			(layers "F.Cu" "F.Mask" "F.Paste")
			(net "PWRGD_P1V26_STBY")
		)
		(pad "4" smd rect
			(at -0.50038 -1.5494 90)
			(size 0.3048 0.9144)
			(layers "F.Cu" "F.Mask" "F.Paste")
			(net "VR_P1V26_STBY_BIAS")
		)
		(pad "5" smd rect
			(at -0.99949 -1.5494 90)
			(size 0.3048 0.9144)
			(layers "F.Cu" "F.Mask" "F.Paste")
			(net "VR_P1V26_STBY_EN_R")
		)
		(pad "6" smd rect
			(at -0.99949 1.5494 90)
			(size 0.3048 0.9144)
			(layers "F.Cu" "F.Mask" "F.Paste")
			(net "GND")
		)
		(pad "7" smd rect
			(at -0.50038 1.5494 90)
			(size 0.3048 0.9144)
			(layers "F.Cu" "F.Mask" "F.Paste")
			(net "VR_P1V26_STBY_SS_C")
		)
		(pad "8" smd rect
			(at 0 1.5494 90)
			(size 0.3048 0.9144)
			(layers "F.Cu" "F.Mask" "F.Paste")
			(net "VR_P1V26_STBY_FB")
		)
		(pad "9" smd rect
			(at 0.50038 1.5494 90)
			(size 0.3048 0.9144)
			(layers "F.Cu" "F.Mask" "F.Paste")
			(net "P1V26_PWR")
		)
		(pad "10" smd rect
			(at 0.99949 1.5494 90)
			(size 0.3048 0.9144)
			(layers "F.Cu" "F.Mask" "F.Paste")
			(net "P1V26_PWR")
		)
		(pad "11" smd custom
			(at 0 0 90)
			(size 0.4318 0.4318)
			(layers "F.Cu" "F.Mask" "F.Paste")
			(net "GND")
			(options
				(clearance outline)
				(anchor circle)
			)
			(primitives
				(gr_poly
					(pts
						(xy -1.2446 0.8636) (xy -1.2446 0.3937) (xy -1.8796 0.3937) (xy -1.8796 0.1143) (xy -1.2446 0.1143)
						(xy -1.2446 -0.1143) (xy -1.8796 -0.1143) (xy -1.8796 -0.3937) (xy -1.2446 -0.3937) (xy -1.2446 -0.8636)
						(xy 1.2446 -0.8636) (xy 1.2446 -0.3937) (xy 1.8796 -0.3937) (xy 1.8796 -0.1143) (xy 1.2446 -0.1143)
						(xy 1.2446 0.1143) (xy 1.8796 0.1143) (xy 1.8796 0.3937) (xy 1.2446 0.3937) (xy 1.2446 0.8636)
					)
					(width 0)
					(fill yes)
				)
			)
		)
	)
	(footprint ""
		(layer "F.Cu")
		(at 127.992886 -84.211414 90)
		(property "Reference" "U43"
			(at 0 0 90)
			(layer "F.SilkS")
			(hide yes)
			(effects
				(font
					(size 1.27 1.27)
				)
			)
		)
		(property "Value" "PCF8563T-1-GP"
			(at -3.707384 -1.5367 90)
			(unlocked yes)
			(layer "F.Fab")
			(hide yes)
			(effects
				(font
					(size 1.016 1.016)
					(thickness 0.1524)
				)
			)
		)
		(property "Device Type" "SOIC8H69"
			(at -3.707384 -3.0607 90)
			(unlocked yes)
			(layer "F.Fab")
			(hide yes)
			(effects
				(font
					(size 1.016 1.016)
					(thickness 0.1524)
				)
			)
		)
		(duplicate_pad_numbers_are_jumpers no)
		(fp_line
			(start 2.1336 -1.4224)
			(end -2.7432 -1.4224)
			(stroke
				(width 0.1524)
				(type default)
			)
			(layer "F.SilkS")
		)
		(fp_line
			(start -2.7432 -1.4224)
			(end -2.7432 1.4224)
			(stroke
				(width 0.1524)
				(type default)
			)
			(layer "F.SilkS")
		)
		(fp_line
			(start -2.7178 -0.508)
			(end -2.1844 -0.0508)
			(stroke
				(width 0.1524)
				(type default)
			)
			(layer "F.SilkS")
		)
		(fp_line
			(start -2.1844 -0.0508)
			(end -2.7178 0.508)
			(stroke
				(width 0.1524)
				(type default)
			)
			(layer "F.SilkS")
		)
		(fp_line
			(start 2.1336 1.4224)
			(end 2.1336 -1.4224)
			(stroke
				(width 0.1524)
				(type default)
			)
			(layer "F.SilkS")
		)
		(fp_line
			(start -2.7432 1.4224)
			(end 2.1336 1.4224)
			(stroke
				(width 0.1524)
				(type default)
			)
			(layer "F.SilkS")
		)
		(fp_line
			(start -2.7432 1.4224)
			(end -2.6416 1.4224)
			(stroke
				(width 0.1524)
				(type default)
			)
			(layer "F.SilkS")
		)
		(fp_line
			(start -2.6289 3.4417)
			(end -2.6289 1.4732)
			(stroke
				(width 0.381)
				(type default)
			)
			(layer "F.SilkS")
		)
		(fp_poly
			(pts
				(xy -2.2098 -1.4224) (xy -2.2098 1.4224) (xy 2.2098 1.4224) (xy 2.2098 -1.4224)
			)
			(stroke
				(width 0)
				(type default)
			)
			(fill yes)
			(layer "F.SilkS")
		)
		(fp_rect
			(start -2.450084 2.999994)
			(end 2.450084 -2.999994)
			(stroke
				(width 0)
				(type default)
			)
			(fill no)
			(layer "F.CrtYd")
		)
		(fp_poly
			(pts
				(xy -2.8194 3.6322) (xy -2.8194 -3.6322) (xy 2.8194 -3.6322) (xy 2.8194 1.18364) (xy 2.450084 1.18364)
				(xy 2.450084 -2.999994) (xy -2.450084 -2.999994) (xy -2.450084 2.999994) (xy 2.450084 2.999994)
				(xy 2.450084 1.18618) (xy 2.8194 1.18618) (xy 2.8194 3.6322)
			)
			(stroke
				(width 0)
				(type default)
			)
			(fill no)
			(layer "F.CrtYd")
		)
		(fp_rect
			(start -2.8194 3.6322)
			(end 2.8194 -3.6322)
			(stroke
				(width 0)
				(type default)
			)
			(fill no)
			(layer "F.Fab")
		)
		(pad "1" smd rect
			(at -1.905 2.54 90)
			(size 0.635 1.651)
			(layers "F.Cu" "F.Mask" "F.Paste")
			(net "RTC_OSCI")
		)
		(pad "2" smd rect
			(at -0.635 2.54 90)
			(size 0.635 1.651)
			(layers "F.Cu" "F.Mask" "F.Paste")
			(net "RTC_OSCO")
		)
		(pad "3" smd rect
			(at 0.635 2.54 90)
			(size 0.635 1.651)
			(layers "F.Cu" "F.Mask" "F.Paste")
			(net "RTC_INT_N")
		)
		(pad "4" smd rect
			(at 1.905 2.54 90)
			(size 0.635 1.651)
			(layers "F.Cu" "F.Mask" "F.Paste")
			(net "GND")
		)
		(pad "5" smd rect
			(at 1.905 -2.54 90)
			(size 0.635 1.651)
			(layers "F.Cu" "F.Mask" "F.Paste")
			(net "RTC_I2C_SDA")
		)
		(pad "6" smd rect
			(at 0.635 -2.54 90)
			(size 0.635 1.651)
			(layers "F.Cu" "F.Mask" "F.Paste")
			(net "RTC_I2C_SCL")
		)
		(pad "7" smd rect
			(at -0.635 -2.54 90)
			(size 0.635 1.651)
			(layers "F.Cu" "F.Mask" "F.Paste")
			(net "RTC_CLK_OUT")
		)
		(pad "8" smd rect
			(at -1.905 -2.54 90)
			(size 0.635 1.651)
			(layers "F.Cu" "F.Mask" "F.Paste")
			(net "P3V3_RTC")
		)
	)
	(footprint ""
		(layer "F.Cu")
		(at 299.808138 -212.420454 180)
		(property "Reference" "C77"
			(at 0 0 180)
			(layer "F.SilkS")
			(hide yes)
			(effects
				(font
					(size 1.27 1.27)
				)
			)
		)
		(property "Value" "SCD22U10V2KX-1GP"
			(at 1.1811 -2.7051 180)
			(unlocked yes)
			(layer "F.Fab")
			(hide yes)
			(effects
				(font
					(size 1.016 1.016)
					(thickness 0.1524)
				)
			)
		)
		(property "Device Type" "C402H22"
			(at 1.1811 -4.2291 180)
			(unlocked yes)
			(layer "F.Fab")
			(hide yes)
			(effects
				(font
					(size 1.016 1.016)
					(thickness 0.1524)
				)
			)
		)
		(duplicate_pad_numbers_are_jumpers no)
		(fp_rect
			(start -0.4318 0.9525)
			(end 0.4318 -0.9525)
			(stroke
				(width 0)
				(type default)
			)
			(fill no)
			(layer "F.CrtYd")
		)
		(fp_rect
			(start -0.4318 0.9525)
			(end 0.4318 -0.9525)
			(stroke
				(width 0)
				(type default)
			)
			(fill no)
			(layer "F.Fab")
		)
		(pad "1" smd custom
			(at 0 -0.4445 180)
			(size 0.1524 0.1524)
			(layers "F.Cu" "F.Mask" "F.Paste")
			(net "PCIE_TX_CAP_N27")
			(options
				(clearance outline)
				(anchor circle)
			)
			(primitives
				(gr_poly
					(pts
						(arc
							(start 0.3048 -0.2032)
							(mid 0.275042 -0.275042)
							(end 0.2032 -0.3048)
						)
						(arc
							(start -0.2032 -0.3048)
							(mid -0.275042 -0.275042)
							(end -0.3048 -0.2032)
						)
						(arc
							(start -0.3048 0.2032)
							(mid -0.275042 0.275042)
							(end -0.2032 0.3048)
						)
						(arc
							(start 0.2032 0.3048)
							(mid 0.275042 0.275042)
							(end 0.3048 0.2032)
						)
					)
					(width 0)
					(fill yes)
				)
			)
		)
		(pad "2" smd custom
			(at 0 0.4445 180)
			(size 0.1524 0.1524)
			(layers "F.Cu" "F.Mask" "F.Paste")
			(net "PCIE_TX_N27")
			(options
				(clearance outline)
				(anchor circle)
			)
			(primitives
				(gr_poly
					(pts
						(arc
							(start 0.3048 -0.2032)
							(mid 0.275042 -0.275042)
							(end 0.2032 -0.3048)
						)
						(arc
							(start -0.2032 -0.3048)
							(mid -0.275042 -0.275042)
							(end -0.3048 -0.2032)
						)
						(arc
							(start -0.3048 0.2032)
							(mid -0.275042 0.275042)
							(end -0.2032 0.3048)
						)
						(arc
							(start 0.2032 0.3048)
							(mid 0.275042 0.275042)
							(end 0.3048 0.2032)
						)
					)
					(width 0)
					(fill yes)
				)
			)
		)
	)
	(footprint ""
		(layer "F.Cu")
		(at 339.1154 -36.49218)
		(property "Reference" "R626"
			(at 0 0 0)
			(layer "F.SilkS")
			(hide yes)
			(effects
				(font
					(size 1.27 1.27)
				)
			)
		)
		(property "Value" "0R2J-2-GP"
			(at 0.064008 -3.993896 0)
			(unlocked yes)
			(layer "F.Fab")
			(hide yes)
			(effects
				(font
					(size 1.016 1.016)
					(thickness 0.1524)
				)
			)
		)
		(property "Device Type" "R402H16"
			(at 0.064008 -5.517896 0)
			(unlocked yes)
			(layer "F.Fab")
			(hide yes)
			(effects
				(font
					(size 1.016 1.016)
					(thickness 0.1524)
				)
			)
		)
		(duplicate_pad_numbers_are_jumpers no)
		(fp_line
			(start -0.508 -0.9398)
			(end -0.508 0.9398)
			(stroke
				(width 0.1524)
				(type default)
			)
			(layer "F.SilkS")
		)
		(fp_line
			(start 0.508 -0.9398)
			(end -0.508 -0.9398)
			(stroke
				(width 0.1524)
				(type default)
			)
			(layer "F.SilkS")
		)
		(fp_rect
			(start -0.508 0.9398)
			(end 0.508 -0.9398)
			(stroke
				(width 0)
				(type default)
			)
			(fill no)
			(layer "F.CrtYd")
		)
		(fp_rect
			(start -0.508 0.9398)
			(end 0.508 -0.9398)
			(stroke
				(width 0)
				(type default)
			)
			(fill no)
			(layer "F.Fab")
		)
		(pad "1" smd custom
			(at 0 -0.4445)
			(size 0.1397 0.1397)
			(layers "F.Cu" "F.Mask" "F.Paste")
			(net "UPLINK7_R")
			(options
				(clearance outline)
				(anchor circle)
			)
			(primitives
				(gr_poly
					(pts
						(arc
							(start -0.1778 -0.2794)
							(mid -0.249642 -0.249642)
							(end -0.2794 -0.1778)
						)
						(arc
							(start -0.2794 0.1778)
							(mid -0.249642 0.249642)
							(end -0.1778 0.2794)
						)
						(arc
							(start 0.1778 0.2794)
							(mid 0.249642 0.249642)
							(end 0.2794 0.1778)
						)
						(arc
							(start 0.2794 -0.1778)
							(mid 0.249642 -0.249642)
							(end 0.1778 -0.2794)
						)
					)
					(width 0)
					(fill yes)
				)
			)
		)
		(pad "2" smd custom
			(at 0 0.4445)
			(size 0.1397 0.1397)
			(layers "F.Cu" "F.Mask" "F.Paste")
			(net "UPLINK7")
			(options
				(clearance outline)
				(anchor circle)
			)
			(primitives
				(gr_poly
					(pts
						(arc
							(start -0.1778 -0.2794)
							(mid -0.249642 -0.249642)
							(end -0.2794 -0.1778)
						)
						(arc
							(start -0.2794 0.1778)
							(mid -0.249642 0.249642)
							(end -0.1778 0.2794)
						)
						(arc
							(start 0.1778 0.2794)
							(mid 0.249642 0.249642)
							(end 0.2794 0.1778)
						)
						(arc
							(start 0.2794 -0.1778)
							(mid 0.249642 -0.249642)
							(end 0.1778 -0.2794)
						)
					)
					(width 0)
					(fill yes)
				)
			)
		)
	)
	(footprint ""
		(layer "F.Cu")
		(at 188.208158 -212.420454 180)
		(property "Reference" "C124"
			(at 0 0 180)
			(layer "F.SilkS")
			(hide yes)
			(effects
				(font
					(size 1.27 1.27)
				)
			)
		)
		(property "Value" "SCD22U10V2KX-1GP"
			(at 1.1811 -2.7051 180)
			(unlocked yes)
			(layer "F.Fab")
			(hide yes)
			(effects
				(font
					(size 1.016 1.016)
					(thickness 0.1524)
				)
			)
		)
		(property "Device Type" "C402H22"
			(at 1.1811 -4.2291 180)
			(unlocked yes)
			(layer "F.Fab")
			(hide yes)
			(effects
				(font
					(size 1.016 1.016)
					(thickness 0.1524)
				)
			)
		)
		(duplicate_pad_numbers_are_jumpers no)
		(fp_rect
			(start -0.4318 0.9525)
			(end 0.4318 -0.9525)
			(stroke
				(width 0)
				(type default)
			)
			(fill no)
			(layer "F.CrtYd")
		)
		(fp_rect
			(start -0.4318 0.9525)
			(end 0.4318 -0.9525)
			(stroke
				(width 0)
				(type default)
			)
			(fill no)
			(layer "F.Fab")
		)
		(pad "1" smd custom
			(at 0 -0.4445 180)
			(size 0.1524 0.1524)
			(layers "F.Cu" "F.Mask" "F.Paste")
			(net "PCIE_TX_CAP_N46")
			(options
				(clearance outline)
				(anchor circle)
			)
			(primitives
				(gr_poly
					(pts
						(arc
							(start 0.3048 -0.2032)
							(mid 0.275042 -0.275042)
							(end 0.2032 -0.3048)
						)
						(arc
							(start -0.2032 -0.3048)
							(mid -0.275042 -0.275042)
							(end -0.3048 -0.2032)
						)
						(arc
							(start -0.3048 0.2032)
							(mid -0.275042 0.275042)
							(end -0.2032 0.3048)
						)
						(arc
							(start 0.2032 0.3048)
							(mid 0.275042 0.275042)
							(end 0.3048 0.2032)
						)
					)
					(width 0)
					(fill yes)
				)
			)
		)
		(pad "2" smd custom
			(at 0 0.4445 180)
			(size 0.1524 0.1524)
			(layers "F.Cu" "F.Mask" "F.Paste")
			(net "PCIE_TX_N46")
			(options
				(clearance outline)
				(anchor circle)
			)
			(primitives
				(gr_poly
					(pts
						(arc
							(start 0.3048 -0.2032)
							(mid 0.275042 -0.275042)
							(end 0.2032 -0.3048)
						)
						(arc
							(start -0.2032 -0.3048)
							(mid -0.275042 -0.275042)
							(end -0.3048 -0.2032)
						)
						(arc
							(start -0.3048 0.2032)
							(mid -0.275042 0.275042)
							(end -0.2032 0.3048)
						)
						(arc
							(start 0.2032 0.3048)
							(mid 0.275042 0.275042)
							(end 0.3048 0.2032)
						)
					)
					(width 0)
					(fill yes)
				)
			)
		)
	)
)
